(kicad_pcb
	(version 20260206)
	(generator "pcbnew")
	(generator_version "10.0")
	(general
		(thickness 1.6)
		(legacy_teardrops no)
	)
	(paper "A4")
	(title_block
		(title "dpb — 14545-sa.0730WZS0815.brd")
		(comment 1 "Honey Badger (Wiwynn) / footprints 1027-1033 of 1066")
	)
	(layers
		(0 "F.Cu" signal "TOP")
		(4 "In1.Cu" signal "L2GND")
		(6 "In2.Cu" signal "L3")
		(8 "In3.Cu" signal "L4VCC")
		(10 "In4.Cu" signal "L5VCC")
		(12 "In5.Cu" signal "L6")
		(14 "In6.Cu" signal "L7GND")
		(2 "B.Cu" signal "BOTTOM")
		(9 "F.Adhes" user "F.Adhesive")
		(11 "B.Adhes" user "B.Adhesive")
		(13 "F.Paste" user "Package Geometry/Pastemask Top")
		(15 "B.Paste" user "Package Geometry/Pastemask Bottom")
		(5 "F.SilkS" user "Ref Des/Silkscreen Top")
		(7 "B.SilkS" user "Ref Des/Silkscreen Bottom")
		(1 "F.Mask" user "Board Geometry/Soldermask Top")
		(3 "B.Mask" user "Board Geometry/Soldermask Bottom")
		(17 "Dwgs.User" user "User.Drawings")
		(19 "Cmts.User" user "User.Comments")
		(21 "Eco1.User" user "User.Eco1")
		(23 "Eco2.User" user "User.Eco2")
		(25 "Edge.Cuts" user "Board Geometry/Outline")
		(27 "Margin" user)
		(31 "F.CrtYd" user "Package Geometry/Place Bound Top")
		(29 "B.CrtYd" user "Package Geometry/Place Bound Bottom")
		(35 "F.Fab" user "Ref Des/Assembly Top")
		(33 "B.Fab" user "Ref Des/Assembly Bottom")
	)
	(footprint ""
		(layer "F.Cu")
		(at 45.465746 -217.706702)
		(property "Reference" "C305"
			(at 0 0 0)
			(layer "F.SilkS")
			(hide yes)
			(effects
				(font
					(size 1.27 1.27)
				)
			)
		)
		(property "Value" "SC10U25V6KX-1GP"
			(at -0.0762 -5.1308 0)
			(unlocked yes)
			(layer "F.Fab")
			(hide yes)
			(effects
				(font
					(size 1.016 1.016)
					(thickness 0.1524)
				)
			)
		)
		(property "Device Type" "C1206H71"
			(at -0.127 -6.6548 0)
			(unlocked yes)
			(layer "F.Fab")
			(hide yes)
			(effects
				(font
					(size 1.016 1.016)
					(thickness 0.1524)
				)
			)
		)
		(duplicate_pad_numbers_are_jumpers no)
		(fp_line
			(start -1.016 -2.2352)
			(end 1.016 -2.2352)
			(stroke
				(width 0.1524)
				(type default)
			)
			(layer "F.SilkS")
		)
		(fp_line
			(start -1.016 -0.8382)
			(end -1.016 -2.2352)
			(stroke
				(width 0.1524)
				(type default)
			)
			(layer "F.SilkS")
		)
		(fp_line
			(start -1.016 2.2352)
			(end -1.016 0.8382)
			(stroke
				(width 0.1524)
				(type default)
			)
			(layer "F.SilkS")
		)
		(fp_line
			(start 1.016 -2.2352)
			(end 1.016 -0.8382)
			(stroke
				(width 0.1524)
				(type default)
			)
			(layer "F.SilkS")
		)
		(fp_line
			(start 1.016 0.8382)
			(end 1.016 2.2352)
			(stroke
				(width 0.1524)
				(type default)
			)
			(layer "F.SilkS")
		)
		(fp_line
			(start 1.016 2.2352)
			(end -1.016 2.2352)
			(stroke
				(width 0.1524)
				(type default)
			)
			(layer "F.SilkS")
		)
		(fp_rect
			(start -1.0922 2.3114)
			(end 1.0922 -2.3114)
			(stroke
				(width 0)
				(type default)
			)
			(fill no)
			(layer "F.CrtYd")
		)
		(fp_poly
			(pts
				(xy 1.0922 -2.3114) (xy 1.0922 2.3114) (xy -1.0922 2.3114) (xy -1.0922 -2.3114)
			)
			(stroke
				(width 0)
				(type default)
			)
			(fill no)
			(layer "F.Fab")
		)
		(pad "1" smd rect
			(at 0 -1.397)
			(size 1.651 1.27)
			(layers "F.Cu" "F.Mask" "F.Paste")
			(net "P12V_HDD12")
		)
		(pad "2" smd rect
			(at 0 1.397)
			(size 1.651 1.27)
			(layers "F.Cu" "F.Mask" "F.Paste")
			(net "GND")
		)
	)
	(footprint ""
		(layer "F.Cu")
		(at 48.386746 -214.404702)
		(property "Reference" "R278"
			(at 0 0 0)
			(layer "F.SilkS")
			(hide yes)
			(effects
				(font
					(size 1.27 1.27)
				)
			)
		)
		(property "Value" "4K7R2J-2-GP"
			(at 0.064008 -3.993896 0)
			(unlocked yes)
			(layer "F.Fab")
			(hide yes)
			(effects
				(font
					(size 1.016 1.016)
					(thickness 0.1524)
				)
			)
		)
		(property "Device Type" "R402H16"
			(at 0.064008 -5.517896 0)
			(unlocked yes)
			(layer "F.Fab")
			(hide yes)
			(effects
				(font
					(size 1.016 1.016)
					(thickness 0.1524)
				)
			)
		)
		(duplicate_pad_numbers_are_jumpers no)
		(fp_line
			(start -0.508 -0.9398)
			(end -0.508 0.9398)
			(stroke
				(width 0.1524)
				(type default)
			)
			(layer "F.SilkS")
		)
		(fp_line
			(start 0.508 -0.9398)
			(end -0.508 -0.9398)
			(stroke
				(width 0.1524)
				(type default)
			)
			(layer "F.SilkS")
		)
		(fp_rect
			(start -0.508 0.9398)
			(end 0.508 -0.9398)
			(stroke
				(width 0)
				(type default)
			)
			(fill no)
			(layer "F.CrtYd")
		)
		(fp_rect
			(start -0.508 0.9398)
			(end 0.508 -0.9398)
			(stroke
				(width 0)
				(type default)
			)
			(fill no)
			(layer "F.Fab")
		)
		(pad "1" smd custom
			(at 0 -0.4445)
			(size 0.1397 0.1397)
			(layers "F.Cu" "F.Mask" "F.Paste")
			(net "P12V")
			(options
				(clearance outline)
				(anchor circle)
			)
			(primitives
				(gr_poly
					(pts
						(arc
							(start -0.1778 -0.2794)
							(mid -0.249642 -0.249642)
							(end -0.2794 -0.1778)
						)
						(arc
							(start -0.2794 0.1778)
							(mid -0.249642 0.249642)
							(end -0.1778 0.2794)
						)
						(arc
							(start 0.1778 0.2794)
							(mid 0.249642 0.249642)
							(end 0.2794 0.1778)
						)
						(arc
							(start 0.2794 -0.1778)
							(mid 0.249642 -0.249642)
							(end 0.1778 -0.2794)
						)
					)
					(width 0)
					(fill yes)
				)
			)
		)
		(pad "2" smd custom
			(at 0 0.4445)
			(size 0.1397 0.1397)
			(layers "F.Cu" "F.Mask" "F.Paste")
			(net "SW_HDD12_R")
			(options
				(clearance outline)
				(anchor circle)
			)
			(primitives
				(gr_poly
					(pts
						(arc
							(start -0.1778 -0.2794)
							(mid -0.249642 -0.249642)
							(end -0.2794 -0.1778)
						)
						(arc
							(start -0.2794 0.1778)
							(mid -0.249642 0.249642)
							(end -0.1778 0.2794)
						)
						(arc
							(start 0.1778 0.2794)
							(mid 0.249642 0.249642)
							(end 0.2794 0.1778)
						)
						(arc
							(start 0.2794 -0.1778)
							(mid 0.249642 -0.249642)
							(end 0.1778 -0.2794)
						)
					)
					(width 0)
					(fill yes)
				)
			)
		)
	)
	(footprint ""
		(layer "F.Cu")
		(at 228.726746 -21.9837 180)
		(property "Reference" "PR49"
			(at 0 0 180)
			(layer "F.SilkS")
			(hide yes)
			(effects
				(font
					(size 1.27 1.27)
				)
			)
		)
		(property "Value" "10KR2F-2-GP"
			(at 0.064008 -3.993896 180)
			(unlocked yes)
			(layer "F.Fab")
			(hide yes)
			(effects
				(font
					(size 1.016 1.016)
					(thickness 0.1524)
				)
			)
		)
		(property "Device Type" "R402H16"
			(at 0.064008 -5.517896 180)
			(unlocked yes)
			(layer "F.Fab")
			(hide yes)
			(effects
				(font
					(size 1.016 1.016)
					(thickness 0.1524)
				)
			)
		)
		(duplicate_pad_numbers_are_jumpers no)
		(fp_line
			(start 0.508 -0.9398)
			(end -0.508 -0.9398)
			(stroke
				(width 0.1524)
				(type default)
			)
			(layer "F.SilkS")
		)
		(fp_line
			(start -0.508 -0.9398)
			(end -0.508 0.9398)
			(stroke
				(width 0.1524)
				(type default)
			)
			(layer "F.SilkS")
		)
		(fp_rect
			(start -0.508 0.9398)
			(end 0.508 -0.9398)
			(stroke
				(width 0)
				(type default)
			)
			(fill no)
			(layer "F.CrtYd")
		)
		(fp_rect
			(start -0.508 0.9398)
			(end 0.508 -0.9398)
			(stroke
				(width 0)
				(type default)
			)
			(fill no)
			(layer "F.Fab")
		)
		(pad "1" smd custom
			(at 0 -0.4445 180)
			(size 0.1397 0.1397)
			(layers "F.Cu" "F.Mask" "F.Paste")
			(net "P5VA_LL")
			(options
				(clearance outline)
				(anchor circle)
			)
			(primitives
				(gr_poly
					(pts
						(arc
							(start -0.1778 -0.2794)
							(mid -0.249642 -0.249642)
							(end -0.2794 -0.1778)
						)
						(arc
							(start -0.2794 0.1778)
							(mid -0.249642 0.249642)
							(end -0.1778 0.2794)
						)
						(arc
							(start 0.1778 0.2794)
							(mid 0.249642 0.249642)
							(end 0.2794 0.1778)
						)
						(arc
							(start 0.2794 -0.1778)
							(mid 0.249642 -0.249642)
							(end 0.1778 -0.2794)
						)
					)
					(width 0)
					(fill yes)
				)
			)
		)
		(pad "2" smd custom
			(at 0 0.4445 180)
			(size 0.1397 0.1397)
			(layers "F.Cu" "F.Mask" "F.Paste")
			(net "P5VA_LL_NET")
			(options
				(clearance outline)
				(anchor circle)
			)
			(primitives
				(gr_poly
					(pts
						(arc
							(start -0.1778 -0.2794)
							(mid -0.249642 -0.249642)
							(end -0.2794 -0.1778)
						)
						(arc
							(start -0.2794 0.1778)
							(mid -0.249642 0.249642)
							(end -0.1778 0.2794)
						)
						(arc
							(start 0.1778 0.2794)
							(mid 0.249642 0.249642)
							(end 0.2794 0.1778)
						)
						(arc
							(start 0.2794 -0.1778)
							(mid 0.249642 -0.249642)
							(end 0.1778 -0.2794)
						)
					)
					(width 0)
					(fill yes)
				)
			)
		)
	)
	(footprint ""
		(layer "F.Cu")
		(at 32.892746 -340.8807 -90)
		(property "Reference" "R501"
			(at 0 0 270)
			(layer "F.SilkS")
			(hide yes)
			(effects
				(font
					(size 1.27 1.27)
				)
			)
		)
		(property "Value" "1KR2F-3-GP"
			(at 0.064008 -3.993896 270)
			(unlocked yes)
			(layer "F.Fab")
			(hide yes)
			(effects
				(font
					(size 1.016 1.016)
					(thickness 0.1524)
				)
			)
		)
		(property "Device Type" "R402H16"
			(at 0.064008 -5.517896 270)
			(unlocked yes)
			(layer "F.Fab")
			(hide yes)
			(effects
				(font
					(size 1.016 1.016)
					(thickness 0.1524)
				)
			)
		)
		(duplicate_pad_numbers_are_jumpers no)
		(fp_line
			(start -0.508 -0.9398)
			(end -0.508 0.9398)
			(stroke
				(width 0.1524)
				(type default)
			)
			(layer "F.SilkS")
		)
		(fp_line
			(start 0.508 -0.9398)
			(end -0.508 -0.9398)
			(stroke
				(width 0.1524)
				(type default)
			)
			(layer "F.SilkS")
		)
		(fp_rect
			(start -0.508 0.9398)
			(end 0.508 -0.9398)
			(stroke
				(width 0)
				(type default)
			)
			(fill no)
			(layer "F.CrtYd")
		)
		(fp_rect
			(start -0.508 0.9398)
			(end 0.508 -0.9398)
			(stroke
				(width 0)
				(type default)
			)
			(fill no)
			(layer "F.Fab")
		)
		(pad "1" smd custom
			(at 0 -0.4445 270)
			(size 0.1397 0.1397)
			(layers "F.Cu" "F.Mask" "F.Paste")
			(net "FLT_HDD11_B")
			(options
				(clearance outline)
				(anchor circle)
			)
			(primitives
				(gr_poly
					(pts
						(arc
							(start -0.1778 -0.2794)
							(mid -0.249642 -0.249642)
							(end -0.2794 -0.1778)
						)
						(arc
							(start -0.2794 0.1778)
							(mid -0.249642 0.249642)
							(end -0.1778 0.2794)
						)
						(arc
							(start 0.1778 0.2794)
							(mid 0.249642 0.249642)
							(end 0.2794 0.1778)
						)
						(arc
							(start 0.2794 -0.1778)
							(mid 0.249642 -0.249642)
							(end 0.1778 -0.2794)
						)
					)
					(width 0)
					(fill yes)
				)
			)
		)
		(pad "2" smd custom
			(at 0 0.4445 270)
			(size 0.1397 0.1397)
			(layers "F.Cu" "F.Mask" "F.Paste")
			(net "FLT_HDD11_DRIVE")
			(options
				(clearance outline)
				(anchor circle)
			)
			(primitives
				(gr_poly
					(pts
						(arc
							(start -0.1778 -0.2794)
							(mid -0.249642 -0.249642)
							(end -0.2794 -0.1778)
						)
						(arc
							(start -0.2794 0.1778)
							(mid -0.249642 0.249642)
							(end -0.1778 0.2794)
						)
						(arc
							(start 0.1778 0.2794)
							(mid 0.249642 0.249642)
							(end 0.2794 0.1778)
						)
						(arc
							(start 0.2794 -0.1778)
							(mid 0.249642 -0.249642)
							(end 0.1778 -0.2794)
						)
					)
					(width 0)
					(fill yes)
				)
			)
		)
	)
	(footprint ""
		(layer "F.Cu")
		(at 52.323746 -225.6917)
		(property "Reference" "U37"
			(at 0 0 0)
			(layer "F.SilkS")
			(hide yes)
			(effects
				(font
					(size 1.27 1.27)
				)
			)
		)
		(property "Value" "74LVC1G08GW-1-GP"
			(at -2.3368 -8.6868 0)
			(unlocked yes)
			(layer "F.Fab")
			(hide yes)
			(effects
				(font
					(size 1.016 1.016)
					(thickness 0.1524)
				)
			)
		)
		(property "Device Type" "SC70-5H44"
			(at -2.3114 -10.414 0)
			(unlocked yes)
			(layer "F.Fab")
			(hide yes)
			(effects
				(font
					(size 1.016 1.016)
					(thickness 0.1524)
				)
			)
		)
		(duplicate_pad_numbers_are_jumpers no)
		(fp_line
			(start -1.27 -1.7018)
			(end 1.27 -1.7018)
			(stroke
				(width 0.1524)
				(type default)
			)
			(layer "F.SilkS")
		)
		(fp_line
			(start -1.27 1.7018)
			(end -1.27 -1.7018)
			(stroke
				(width 0.1524)
				(type default)
			)
			(layer "F.SilkS")
		)
		(fp_line
			(start 0.6604 -1.8034)
			(end 1.3843 -1.8034)
			(stroke
				(width 0.3302)
				(type default)
			)
			(layer "F.SilkS")
		)
		(fp_line
			(start 1.27 -1.7018)
			(end 1.27 1.7018)
			(stroke
				(width 0.1524)
				(type default)
			)
			(layer "F.SilkS")
		)
		(fp_line
			(start 1.27 1.7018)
			(end -1.27 1.7018)
			(stroke
				(width 0.1524)
				(type default)
			)
			(layer "F.SilkS")
		)
		(fp_line
			(start 1.3843 -1.8034)
			(end 1.3843 -1.1176)
			(stroke
				(width 0.3302)
				(type default)
			)
			(layer "F.SilkS")
		)
		(fp_rect
			(start -1.524 1.9558)
			(end 1.524 -1.9558)
			(stroke
				(width 0)
				(type default)
			)
			(fill no)
			(layer "F.CrtYd")
		)
		(fp_poly
			(pts
				(xy -1.524 -1.9558) (xy 1.524 -1.9558) (xy 1.524 1.9558) (xy -1.524 1.9558)
			)
			(stroke
				(width 0)
				(type default)
			)
			(fill no)
			(layer "F.Fab")
		)
		(pad "1" smd rect
			(at 0.65024 -0.8255)
			(size 0.4064 1.2192)
			(layers "F.Cu" "F.Mask" "F.Paste")
			(net "SAS2X28_B_HDD12_FLT")
		)
		(pad "2" smd rect
			(at 0 -0.8255)
			(size 0.4064 1.2192)
			(layers "F.Cu" "F.Mask" "F.Paste")
			(net "SAS2X28_A_HDD12_FLT")
		)
		(pad "3" smd rect
			(at -0.65024 -0.8255)
			(size 0.4064 1.2192)
			(layers "F.Cu" "F.Mask" "F.Paste")
			(net "GND")
		)
		(pad "4" smd rect
			(at -0.65024 0.8255)
			(size 0.4064 1.2192)
			(layers "F.Cu" "F.Mask" "F.Paste")
			(net "FLT_HDD12_DRIVE")
		)
		(pad "5" smd rect
			(at 0.65024 0.8255)
			(size 0.4064 1.2192)
			(layers "F.Cu" "F.Mask" "F.Paste")
			(net "P3V3")
		)
	)
	(footprint ""
		(layer "F.Cu")
		(at 206.104744 -487.13771 90)
		(property "Reference" "Q2"
			(at 0 0 90)
			(layer "F.SilkS")
			(hide yes)
			(effects
				(font
					(size 1.27 1.27)
				)
			)
		)
		(property "Value" "AO4406AL-GP"
			(at -3.707384 -1.5367 90)
			(unlocked yes)
			(layer "F.Fab")
			(hide yes)
			(effects
				(font
					(size 1.016 1.016)
					(thickness 0.1524)
				)
			)
		)
		(property "Device Type" "SOIC8H69"
			(at -3.707384 -3.0607 90)
			(unlocked yes)
			(layer "F.Fab")
			(hide yes)
			(effects
				(font
					(size 1.016 1.016)
					(thickness 0.1524)
				)
			)
		)
		(duplicate_pad_numbers_are_jumpers no)
		(fp_line
			(start 2.1336 -1.4224)
			(end -2.7432 -1.4224)
			(stroke
				(width 0.1524)
				(type default)
			)
			(layer "F.SilkS")
		)
		(fp_line
			(start -2.7432 -1.4224)
			(end -2.7432 1.4224)
			(stroke
				(width 0.1524)
				(type default)
			)
			(layer "F.SilkS")
		)
		(fp_line
			(start -2.7178 -0.508)
			(end -2.1844 -0.0508)
			(stroke
				(width 0.1524)
				(type default)
			)
			(layer "F.SilkS")
		)
		(fp_line
			(start -2.1844 -0.0508)
			(end -2.7178 0.508)
			(stroke
				(width 0.1524)
				(type default)
			)
			(layer "F.SilkS")
		)
		(fp_line
			(start 2.1336 1.4224)
			(end 2.1336 -1.4224)
			(stroke
				(width 0.1524)
				(type default)
			)
			(layer "F.SilkS")
		)
		(fp_line
			(start -2.7432 1.4224)
			(end 2.1336 1.4224)
			(stroke
				(width 0.1524)
				(type default)
			)
			(layer "F.SilkS")
		)
		(fp_line
			(start -2.7432 1.4224)
			(end -2.6416 1.4224)
			(stroke
				(width 0.1524)
				(type default)
			)
			(layer "F.SilkS")
		)
		(fp_line
			(start -2.6289 3.4417)
			(end -2.6289 1.4732)
			(stroke
				(width 0.381)
				(type default)
			)
			(layer "F.SilkS")
		)
		(fp_poly
			(pts
				(xy -2.2098 -1.4224) (xy -2.2098 1.4224) (xy 2.2098 1.4224) (xy 2.2098 -1.4224)
			)
			(stroke
				(width 0)
				(type default)
			)
			(fill yes)
			(layer "F.SilkS")
		)
		(fp_rect
			(start -2.450084 2.999994)
			(end 2.450084 -2.999994)
			(stroke
				(width 0)
				(type default)
			)
			(fill no)
			(layer "F.CrtYd")
		)
		(fp_poly
			(pts
				(xy -2.8194 3.6322) (xy -2.8194 -3.6322) (xy 2.8194 -3.6322) (xy 2.8194 1.18364) (xy 2.450084 1.18364)
				(xy 2.450084 -2.999994) (xy -2.450084 -2.999994) (xy -2.450084 2.999994) (xy 2.450084 2.999994)
				(xy 2.450084 1.18618) (xy 2.8194 1.18618) (xy 2.8194 3.6322)
			)
			(stroke
				(width 0)
				(type default)
			)
			(fill no)
			(layer "F.CrtYd")
		)
		(fp_rect
			(start -2.8194 3.6322)
			(end 2.8194 -3.6322)
			(stroke
				(width 0)
				(type default)
			)
			(fill no)
			(layer "F.Fab")
		)
		(pad "1" smd rect
			(at -1.905 2.54 90)
			(size 0.635 1.651)
			(layers "F.Cu" "F.Mask" "F.Paste")
			(net "P5V_HDD0")
		)
		(pad "2" smd rect
			(at -0.635 2.54 90)
			(size 0.635 1.651)
			(layers "F.Cu" "F.Mask" "F.Paste")
			(net "P5V_HDD0")
		)
		(pad "3" smd rect
			(at 0.635 2.54 90)
			(size 0.635 1.651)
			(layers "F.Cu" "F.Mask" "F.Paste")
			(net "P5V_HDD0")
		)
		(pad "4" smd rect
			(at 1.905 2.54 90)
			(size 0.635 1.651)
			(layers "F.Cu" "F.Mask" "F.Paste")
			(net "SW_HDD0_P")
		)
		(pad "5" smd rect
			(at 1.905 -2.54 90)
			(size 0.635 1.651)
			(layers "F.Cu" "F.Mask" "F.Paste")
			(net "P5VA")
		)
		(pad "6" smd rect
			(at 0.635 -2.54 90)
			(size 0.635 1.651)
			(layers "F.Cu" "F.Mask" "F.Paste")
			(net "P5VA")
		)
		(pad "7" smd rect
			(at -0.635 -2.54 90)
			(size 0.635 1.651)
			(layers "F.Cu" "F.Mask" "F.Paste")
			(net "P5VA")
		)
		(pad "8" smd rect
			(at -1.905 -2.54 90)
			(size 0.635 1.651)
			(layers "F.Cu" "F.Mask" "F.Paste")
			(net "P5VA")
		)
	)
	(footprint ""
		(layer "F.Cu")
		(at 10.8204 -476.7072)
		(property "Reference" "R608"
			(at 0 0 0)
			(layer "F.SilkS")
			(hide yes)
			(effects
				(font
					(size 1.27 1.27)
				)
			)
		)
		(property "Value" "2R2010J-1-GP"
			(at 0.254 -8.0772 0)
			(unlocked yes)
			(layer "F.Fab")
			(hide yes)
			(effects
				(font
					(size 1.016 1.016)
					(thickness 0.1524)
				)
			)
		)
		(property "Device Type" "R2010H28"
			(at 0.254 -9.6774 0)
			(unlocked yes)
			(layer "F.Fab")
			(hide yes)
			(effects
				(font
					(size 1.016 1.016)
					(thickness 0.1524)
				)
			)
		)
		(duplicate_pad_numbers_are_jumpers no)
		(fp_line
			(start -1.651 -3.302)
			(end -1.651 3.302)
			(stroke
				(width 0.1524)
				(type default)
			)
			(layer "F.SilkS")
		)
		(fp_line
			(start -1.651 3.302)
			(end 1.651 3.302)
			(stroke
				(width 0.1524)
				(type default)
			)
			(layer "F.SilkS")
		)
		(fp_line
			(start 1.651 -3.302)
			(end -1.651 -3.302)
			(stroke
				(width 0.1524)
				(type default)
			)
			(layer "F.SilkS")
		)
		(fp_line
			(start 1.651 3.302)
			(end 1.651 -3.302)
			(stroke
				(width 0.1524)
				(type default)
			)
			(layer "F.SilkS")
		)
		(fp_rect
			(start -1.7272 -3.3782)
			(end 1.7272 3.3782)
			(stroke
				(width 0)
				(type default)
			)
			(fill no)
			(layer "F.CrtYd")
		)
		(fp_poly
			(pts
				(xy 1.7272 3.3782) (xy 1.7272 -3.3782) (xy -1.7272 -3.3782) (xy -1.7272 3.3782)
			)
			(stroke
				(width 0)
				(type default)
			)
			(fill no)
			(layer "F.Fab")
		)
		(pad "1" smd rect
			(at 0 -2.3495)
			(size 2.794 1.143)
			(layers "F.Cu" "F.Mask" "F.Paste")
			(net "GND")
		)
		(pad "2" smd rect
			(at 0 2.3495)
			(size 2.794 1.143)
			(layers "F.Cu" "F.Mask" "F.Paste")
			(net "PCIE_MATED#_A")
		)
	)
)
